# SCM (Grand Teton) — schematic netlist excerpt (pin names and nets, part order shuffled) for the footprints in the layout excerpt that follows; sources: Cadence DE-HDL packaged netlist, KiCad conversion of 12092022_DA0F0TMDCD0_F0T_Management_Board_D_brd_V3_OCP.brd

R715  Q_RES  33.2 1% CHIP  pkg 0402LF  page 30 : A = UART_BMC_5_TXD_BUF1 ; B = UART_BMC_5_TXD_BUF1_R
R470  Q_RES  0 5% EMPTY  pkg 0402LF  page 50 : A = REAR_AC_PWR_BTN ; B = REAR_AC_PWR_BTN_N

(kicad_pcb
	(version 20260206)
	(generator "pcbnew")
	(generator_version "10.0")
	(general
		(thickness 1.6)
		(legacy_teardrops no)
	)
	(paper "A4")
	(title_block
		(title "12092022_DA0F0TMDCD0_F0T_Management_Board_D_brd_V3_OCP.brd")
		(comment 1 "Grand Teton / footprints 416-417 of 1440")
	)
	(layers
		(0 "F.Cu" signal "TOP")
		(4 "In1.Cu" signal "GND")
		(6 "In2.Cu" signal "IN1")
		(8 "In3.Cu" signal "GND1")
		(10 "In4.Cu" signal "IN2")
		(12 "In5.Cu" signal "VCC")
		(14 "In6.Cu" signal "VCC1")
		(16 "In7.Cu" signal "IN3")
		(18 "In8.Cu" signal "GND2")
		(20 "In9.Cu" signal "IN4")
		(22 "In10.Cu" signal "GND3")
		(2 "B.Cu" signal "BOTTOM")
		(9 "F.Adhes" user "F.Adhesive")
		(11 "B.Adhes" user "B.Adhesive")
		(13 "F.Paste" user "Package Geometry/Pastemask Top")
		(15 "B.Paste" user "Package Geometry/Pastemask Bottom")
		(5 "F.SilkS" user "Ref Des/Silkscreen Top")
		(7 "B.SilkS" user "Ref Des/Silkscreen Bottom")
		(1 "F.Mask" user "Board Geometry/Soldermask Top")
		(3 "B.Mask" user "Board Geometry/Soldermask Bottom")
		(17 "Dwgs.User" user "User.Drawings")
		(19 "Cmts.User" user "User.Comments")
		(21 "Eco1.User" user "User.Eco1")
		(23 "Eco2.User" user "User.Eco2")
		(25 "Edge.Cuts" user "Board Geometry/Outline")
		(27 "Margin" user)
		(31 "F.CrtYd" user "Package Geometry/Place Bound Top")
		(29 "B.CrtYd" user "Package Geometry/Place Bound Bottom")
		(35 "F.Fab" user "Ref Des/Assembly Top")
		(33 "B.Fab" user "Ref Des/Assembly Bottom")
	)
	(footprint ""
		(layer "F.Cu")
		(at 27.1272 -65.5574 90)
		(property "Reference" "R715"
			(at 0 0 90)
			(layer "F.SilkS")
			(hide yes)
			(effects
				(font
					(size 1.27 1.27)
				)
			)
		)
		(property "Value" ""
			(at 0 0 90)
			(layer "F.Fab")
			(effects
				(font
					(size 1.27 1.27)
				)
			)
		)
		(duplicate_pad_numbers_are_jumpers no)
		(fp_line
			(start 0.7874 -0.4064)
			(end 0.7874 0.4064)
			(stroke
				(width 0.1524)
				(type default)
			)
			(layer "F.SilkS")
		)
		(fp_line
			(start -0.7874 -0.4064)
			(end 0.7874 -0.4064)
			(stroke
				(width 0.1524)
				(type default)
			)
			(layer "F.SilkS")
		)
		(fp_line
			(start 0.7874 0.4064)
			(end -0.7874 0.4064)
			(stroke
				(width 0.1524)
				(type default)
			)
			(layer "F.SilkS")
		)
		(fp_line
			(start -0.7874 0.4064)
			(end -0.7874 -0.4064)
			(stroke
				(width 0.1524)
				(type default)
			)
			(layer "F.SilkS")
		)
		(fp_line
			(start -0.12065 -0.305054)
			(end -0.12065 -0.2794)
			(stroke
				(width 0.1)
				(type default)
			)
			(layer "F.Fab")
		)
		(fp_line
			(start -0.67945 -0.305054)
			(end -0.12065 -0.305054)
			(stroke
				(width 0.1)
				(type default)
			)
			(layer "F.Fab")
		)
		(fp_line
			(start 0.67945 -0.3048)
			(end 0.67945 0.3048)
			(stroke
				(width 0.1)
				(type default)
			)
			(layer "F.Fab")
		)
		(fp_line
			(start 0.12065 -0.3048)
			(end 0.67945 -0.3048)
			(stroke
				(width 0.1)
				(type default)
			)
			(layer "F.Fab")
		)
		(fp_line
			(start 0.12065 -0.2794)
			(end 0.12065 -0.3048)
			(stroke
				(width 0.1)
				(type default)
			)
			(layer "F.Fab")
		)
		(fp_line
			(start -0.12065 -0.2794)
			(end 0.12065 -0.2794)
			(stroke
				(width 0.1)
				(type default)
			)
			(layer "F.Fab")
		)
		(fp_line
			(start 0.120396 0.2794)
			(end -0.12065 0.2794)
			(stroke
				(width 0.1)
				(type default)
			)
			(layer "F.Fab")
		)
		(fp_line
			(start -0.12065 0.2794)
			(end -0.12065 0.3048)
			(stroke
				(width 0.1)
				(type default)
			)
			(layer "F.Fab")
		)
		(fp_line
			(start 0.67945 0.3048)
			(end 0.120396 0.3048)
			(stroke
				(width 0.1)
				(type default)
			)
			(layer "F.Fab")
		)
		(fp_line
			(start 0.120396 0.3048)
			(end 0.120396 0.2794)
			(stroke
				(width 0.1)
				(type default)
			)
			(layer "F.Fab")
		)
		(fp_line
			(start -0.12065 0.3048)
			(end -0.67945 0.3048)
			(stroke
				(width 0.1)
				(type default)
			)
			(layer "F.Fab")
		)
		(fp_line
			(start -0.67945 0.3048)
			(end -0.67945 -0.305054)
			(stroke
				(width 0.1)
				(type default)
			)
			(layer "F.Fab")
		)
		(pad "1" smd circle
			(at -0.40005 0 90)
			(size 0 0)
			(layers "F.Cu" "F.Mask" "F.Paste")
			(net "UART_BMC_5_TXD_BUF1")
		)
		(pad "2" smd circle
			(at 0.40005 0 90)
			(size 0 0)
			(layers "F.Cu" "F.Mask" "F.Paste")
			(net "UART_BMC_5_TXD_BUF1_R")
		)
	)
	(footprint ""
		(layer "F.Cu")
		(at 71.501 -10.922 90)
		(property "Reference" "R470"
			(at 0 0 90)
			(layer "F.SilkS")
			(hide yes)
			(effects
				(font
					(size 1.27 1.27)
				)
			)
		)
		(property "Value" ""
			(at 0 0 90)
			(layer "F.Fab")
			(effects
				(font
					(size 1.27 1.27)
				)
			)
		)
		(duplicate_pad_numbers_are_jumpers no)
		(fp_line
			(start 0.7874 -0.4064)
			(end 0.7874 0.4064)
			(stroke
				(width 0.1524)
				(type default)
			)
			(layer "F.SilkS")
		)
		(fp_line
			(start -0.7874 -0.4064)
			(end 0.7874 -0.4064)
			(stroke
				(width 0.1524)
				(type default)
			)
			(layer "F.SilkS")
		)
		(fp_line
			(start 0.7874 0.4064)
			(end -0.7874 0.4064)
			(stroke
				(width 0.1524)
				(type default)
			)
			(layer "F.SilkS")
		)
		(fp_line
			(start -0.7874 0.4064)
			(end -0.7874 -0.4064)
			(stroke
				(width 0.1524)
				(type default)
			)
			(layer "F.SilkS")
		)
		(fp_line
			(start -0.12065 -0.305054)
			(end -0.12065 -0.2794)
			(stroke
				(width 0.1)
				(type default)
			)
			(layer "F.Fab")
		)
		(fp_line
			(start -0.67945 -0.305054)
			(end -0.12065 -0.305054)
			(stroke
				(width 0.1)
				(type default)
			)
			(layer "F.Fab")
		)
		(fp_line
			(start 0.67945 -0.3048)
			(end 0.67945 0.3048)
			(stroke
				(width 0.1)
				(type default)
			)
			(layer "F.Fab")
		)
		(fp_line
			(start 0.12065 -0.3048)
			(end 0.67945 -0.3048)
			(stroke
				(width 0.1)
				(type default)
			)
			(layer "F.Fab")
		)
		(fp_line
			(start 0.12065 -0.2794)
			(end 0.12065 -0.3048)
			(stroke
				(width 0.1)
				(type default)
			)
			(layer "F.Fab")
		)
		(fp_line
			(start -0.12065 -0.2794)
			(end 0.12065 -0.2794)
			(stroke
				(width 0.1)
				(type default)
			)
			(layer "F.Fab")
		)
		(fp_line
			(start 0.120396 0.2794)
			(end -0.12065 0.2794)
			(stroke
				(width 0.1)
				(type default)
			)
			(layer "F.Fab")
		)
		(fp_line
			(start -0.12065 0.2794)
			(end -0.12065 0.3048)
			(stroke
				(width 0.1)
				(type default)
			)
			(layer "F.Fab")
		)
		(fp_line
			(start 0.67945 0.3048)
			(end 0.120396 0.3048)
			(stroke
				(width 0.1)
				(type default)
			)
			(layer "F.Fab")
		)
		(fp_line
			(start 0.120396 0.3048)
			(end 0.120396 0.2794)
			(stroke
				(width 0.1)
				(type default)
			)
			(layer "F.Fab")
		)
		(fp_line
			(start -0.12065 0.3048)
			(end -0.67945 0.3048)
			(stroke
				(width 0.1)
				(type default)
			)
			(layer "F.Fab")
		)
		(fp_line
			(start -0.67945 0.3048)
			(end -0.67945 -0.305054)
			(stroke
				(width 0.1)
				(type default)
			)
			(layer "F.Fab")
		)
		(pad "1" smd circle
			(at -0.40005 0 90)
			(size 0 0)
			(layers "F.Cu" "F.Mask" "F.Paste")
			(net "REAR_AC_PWR_BTN")
		)
		(pad "2" smd circle
			(at 0.40005 0 90)
			(size 0 0)
			(layers "F.Cu" "F.Mask" "F.Paste")
			(net "REAR_AC_PWR_BTN_N")
		)
	)
)
